# T6G (Grand Teton) — schematic netlist excerpt (pin names and nets, part order shuffled) for the footprints in the layout excerpt that follows; sources: Cadence DE-HDL packaged netlist, KiCad conversion of 04192023_DAF0TMB3IC0_F0TG_MB_C_brd_V02_OCP.brd

C695  Q_CAP_DIFFBUS  DIFF BUS_0.22UF 6.3V 20% X6S  pkg C0201  page 67 : \1\ = P5E_CPU1_G1_TX_C_DP<7> ; \2\ = P5E_CPU1_G1_TX_DP<7>
R2693  Q_RES  1K 1% EMPTY  pkg 0402LF  page 245 : A = P3V3_AUX ; B = TCA9539_0_ADD1
R1339  Q_RES  0 5% CHIP  pkg 0402LF  page 82 : A = OCP_V3_2_P3V3_P12V_ADC_R_ALERT ; B = OCP_V3_2_P3V3_P12V_ADC_ALERT

(kicad_pcb
	(version 20260206)
	(generator "pcbnew")
	(generator_version "10.0")
	(general
		(thickness 1.6)
		(legacy_teardrops no)
	)
	(paper "A4")
	(title_block
		(title "04192023_DAF0TMB3IC0_F0TG_MB_C_brd_V02_OCP.brd")
		(comment 1 "Grand Teton / footprints 1349-1351 of 8354")
	)
	(layers
		(0 "F.Cu" signal "TOP")
		(4 "In1.Cu" signal "GND")
		(6 "In2.Cu" signal "IN1")
		(8 "In3.Cu" signal "GND1")
		(10 "In4.Cu" signal "IN2")
		(12 "In5.Cu" signal "GND2")
		(14 "In6.Cu" signal "IN3")
		(16 "In7.Cu" signal "GND3")
		(18 "In8.Cu" signal "VCC")
		(20 "In9.Cu" signal "VCC1")
		(22 "In10.Cu" signal "GND4")
		(24 "In11.Cu" signal "IN4")
		(26 "In12.Cu" signal "GND5")
		(28 "In13.Cu" signal "IN5")
		(30 "In14.Cu" signal "GND6")
		(32 "In15.Cu" signal "IN6")
		(34 "In16.Cu" signal "GND7")
		(2 "B.Cu" signal "BOTTOM")
		(9 "F.Adhes" user "F.Adhesive")
		(11 "B.Adhes" user "B.Adhesive")
		(13 "F.Paste" user "Package Geometry/Pastemask Top")
		(15 "B.Paste" user "Package Geometry/Pastemask Bottom")
		(5 "F.SilkS" user "Ref Des/Silkscreen Top")
		(7 "B.SilkS" user "Ref Des/Silkscreen Bottom")
		(1 "F.Mask" user "Board Geometry/Soldermask Top")
		(3 "B.Mask" user "Board Geometry/Soldermask Bottom")
		(17 "Dwgs.User" user "User.Drawings")
		(19 "Cmts.User" user "User.Comments")
		(21 "Eco1.User" user "User.Eco1")
		(23 "Eco2.User" user "User.Eco2")
		(25 "Edge.Cuts" user "Board Geometry/Outline")
		(27 "Margin" user)
		(31 "F.CrtYd" user "Package Geometry/Place Bound Top")
		(29 "B.CrtYd" user "Package Geometry/Place Bound Bottom")
		(35 "F.Fab" user "Ref Des/Assembly Top")
		(33 "B.Fab" user "Ref Des/Assembly Bottom")
	)
	(footprint ""
		(layer "F.Cu")
		(at 177.748946 -413.815022 90)
		(property "Reference" "R2693"
			(at 0 0 90)
			(layer "F.SilkS")
			(hide yes)
			(effects
				(font
					(size 1.27 1.27)
				)
			)
		)
		(property "Value" ""
			(at 0 0 90)
			(layer "F.Fab")
			(effects
				(font
					(size 1.27 1.27)
				)
			)
		)
		(duplicate_pad_numbers_are_jumpers no)
		(fp_line
			(start 0.7874 -0.4064)
			(end 0.7874 0.4064)
			(stroke
				(width 0.1524)
				(type default)
			)
			(layer "F.SilkS")
		)
		(fp_line
			(start -0.7874 -0.4064)
			(end 0.7874 -0.4064)
			(stroke
				(width 0.1524)
				(type default)
			)
			(layer "F.SilkS")
		)
		(fp_line
			(start 0.7874 0.4064)
			(end -0.7874 0.4064)
			(stroke
				(width 0.1524)
				(type default)
			)
			(layer "F.SilkS")
		)
		(fp_line
			(start -0.7874 0.4064)
			(end -0.7874 -0.4064)
			(stroke
				(width 0.1524)
				(type default)
			)
			(layer "F.SilkS")
		)
		(fp_line
			(start -0.12065 -0.305054)
			(end -0.12065 -0.2794)
			(stroke
				(width 0.1)
				(type default)
			)
			(layer "F.Fab")
		)
		(fp_line
			(start -0.67945 -0.305054)
			(end -0.12065 -0.305054)
			(stroke
				(width 0.1)
				(type default)
			)
			(layer "F.Fab")
		)
		(fp_line
			(start 0.67945 -0.3048)
			(end 0.67945 0.3048)
			(stroke
				(width 0.1)
				(type default)
			)
			(layer "F.Fab")
		)
		(fp_line
			(start 0.12065 -0.3048)
			(end 0.67945 -0.3048)
			(stroke
				(width 0.1)
				(type default)
			)
			(layer "F.Fab")
		)
		(fp_line
			(start 0.12065 -0.2794)
			(end 0.12065 -0.3048)
			(stroke
				(width 0.1)
				(type default)
			)
			(layer "F.Fab")
		)
		(fp_line
			(start -0.12065 -0.2794)
			(end 0.12065 -0.2794)
			(stroke
				(width 0.1)
				(type default)
			)
			(layer "F.Fab")
		)
		(fp_line
			(start 0.120396 0.2794)
			(end -0.12065 0.2794)
			(stroke
				(width 0.1)
				(type default)
			)
			(layer "F.Fab")
		)
		(fp_line
			(start -0.12065 0.2794)
			(end -0.12065 0.3048)
			(stroke
				(width 0.1)
				(type default)
			)
			(layer "F.Fab")
		)
		(fp_line
			(start 0.67945 0.3048)
			(end 0.120396 0.3048)
			(stroke
				(width 0.1)
				(type default)
			)
			(layer "F.Fab")
		)
		(fp_line
			(start 0.120396 0.3048)
			(end 0.120396 0.2794)
			(stroke
				(width 0.1)
				(type default)
			)
			(layer "F.Fab")
		)
		(fp_line
			(start -0.12065 0.3048)
			(end -0.67945 0.3048)
			(stroke
				(width 0.1)
				(type default)
			)
			(layer "F.Fab")
		)
		(fp_line
			(start -0.67945 0.3048)
			(end -0.67945 -0.305054)
			(stroke
				(width 0.1)
				(type default)
			)
			(layer "F.Fab")
		)
		(pad "1" smd circle
			(at -0.40005 0 90)
			(size 0 0)
			(layers "F.Cu" "F.Mask" "F.Paste")
			(net "P3V3_AUX")
		)
		(pad "2" smd circle
			(at 0.40005 0 90)
			(size 0 0)
			(layers "F.Cu" "F.Mask" "F.Paste")
			(net "TCA9539_0_ADD1")
		)
	)
	(footprint ""
		(layer "F.Cu")
		(at 38.774878 -16.099536 90)
		(property "Reference" "C695"
			(at 0 0 90)
			(layer "F.SilkS")
			(hide yes)
			(effects
				(font
					(size 1.27 1.27)
				)
			)
		)
		(property "Value" ""
			(at 0 0 90)
			(layer "F.Fab")
			(effects
				(font
					(size 1.27 1.27)
				)
			)
		)
		(duplicate_pad_numbers_are_jumpers no)
		(fp_line
			(start 0.299974 -0.150114)
			(end 0.299974 0.150114)
			(stroke
				(width 0.1)
				(type default)
			)
			(layer "F.Fab")
		)
		(fp_line
			(start -0.299974 -0.150114)
			(end 0.299974 -0.150114)
			(stroke
				(width 0.1)
				(type default)
			)
			(layer "F.Fab")
		)
		(fp_line
			(start 0.299974 0.150114)
			(end -0.299974 0.150114)
			(stroke
				(width 0.1)
				(type default)
			)
			(layer "F.Fab")
		)
		(fp_line
			(start -0.299974 0.150114)
			(end -0.299974 -0.150114)
			(stroke
				(width 0.1)
				(type default)
			)
			(layer "F.Fab")
		)
		(pad "1" smd rect
			(at -0.2667 0 90)
			(size 0.3048 0.381)
			(layers "F.Cu" "F.Mask" "F.Paste")
			(net "P5E_CPU1_G1_TX_C_DP<7>")
		)
		(pad "2" smd rect
			(at 0.2667 0 90)
			(size 0.3048 0.381)
			(layers "F.Cu" "F.Mask" "F.Paste")
			(net "P5E_CPU1_G1_TX_DP<7>")
		)
	)
	(footprint ""
		(layer "F.Cu")
		(at 187.871608 -100.290376 90)
		(property "Reference" "R1339"
			(at 0 0 90)
			(layer "F.SilkS")
			(hide yes)
			(effects
				(font
					(size 1.27 1.27)
				)
			)
		)
		(property "Value" ""
			(at 0 0 90)
			(layer "F.Fab")
			(effects
				(font
					(size 1.27 1.27)
				)
			)
		)
		(duplicate_pad_numbers_are_jumpers no)
		(fp_line
			(start 0.7874 -0.4064)
			(end 0.7874 0.4064)
			(stroke
				(width 0.1524)
				(type default)
			)
			(layer "F.SilkS")
		)
		(fp_line
			(start -0.7874 -0.4064)
			(end 0.7874 -0.4064)
			(stroke
				(width 0.1524)
				(type default)
			)
			(layer "F.SilkS")
		)
		(fp_line
			(start 0.7874 0.4064)
			(end -0.7874 0.4064)
			(stroke
				(width 0.1524)
				(type default)
			)
			(layer "F.SilkS")
		)
		(fp_line
			(start -0.7874 0.4064)
			(end -0.7874 -0.4064)
			(stroke
				(width 0.1524)
				(type default)
			)
			(layer "F.SilkS")
		)
		(fp_line
			(start -0.12065 -0.305054)
			(end -0.12065 -0.2794)
			(stroke
				(width 0.1)
				(type default)
			)
			(layer "F.Fab")
		)
		(fp_line
			(start -0.67945 -0.305054)
			(end -0.12065 -0.305054)
			(stroke
				(width 0.1)
				(type default)
			)
			(layer "F.Fab")
		)
		(fp_line
			(start 0.67945 -0.3048)
			(end 0.67945 0.3048)
			(stroke
				(width 0.1)
				(type default)
			)
			(layer "F.Fab")
		)
		(fp_line
			(start 0.12065 -0.3048)
			(end 0.67945 -0.3048)
			(stroke
				(width 0.1)
				(type default)
			)
			(layer "F.Fab")
		)
		(fp_line
			(start 0.12065 -0.2794)
			(end 0.12065 -0.3048)
			(stroke
				(width 0.1)
				(type default)
			)
			(layer "F.Fab")
		)
		(fp_line
			(start -0.12065 -0.2794)
			(end 0.12065 -0.2794)
			(stroke
				(width 0.1)
				(type default)
			)
			(layer "F.Fab")
		)
		(fp_line
			(start 0.120396 0.2794)
			(end -0.12065 0.2794)
			(stroke
				(width 0.1)
				(type default)
			)
			(layer "F.Fab")
		)
		(fp_line
			(start -0.12065 0.2794)
			(end -0.12065 0.3048)
			(stroke
				(width 0.1)
				(type default)
			)
			(layer "F.Fab")
		)
		(fp_line
			(start 0.67945 0.3048)
			(end 0.120396 0.3048)
			(stroke
				(width 0.1)
				(type default)
			)
			(layer "F.Fab")
		)
		(fp_line
			(start 0.120396 0.3048)
			(end 0.120396 0.2794)
			(stroke
				(width 0.1)
				(type default)
			)
			(layer "F.Fab")
		)
		(fp_line
			(start -0.12065 0.3048)
			(end -0.67945 0.3048)
			(stroke
				(width 0.1)
				(type default)
			)
			(layer "F.Fab")
		)
		(fp_line
			(start -0.67945 0.3048)
			(end -0.67945 -0.305054)
			(stroke
				(width 0.1)
				(type default)
			)
			(layer "F.Fab")
		)
		(pad "1" smd circle
			(at -0.40005 0 90)
			(size 0 0)
			(layers "F.Cu" "F.Mask" "F.Paste")
			(net "OCP_V3_2_P3V3_P12V_ADC_R_ALERT")
		)
		(pad "2" smd circle
			(at 0.40005 0 90)
			(size 0 0)
			(layers "F.Cu" "F.Mask" "F.Paste")
			(net "OCP_V3_2_P3V3_P12V_ADC_ALERT")
		)
	)
)
